(kicad_pcb
	(version 20260206)
	(generator "pcbnew")
	(generator_version "10.0")
	(general
		(thickness 1.21888)
		(legacy_teardrops no)
	)
	(paper "A4")
	(title_block
		(title "timecard-v7 — TimeCard-DC-V7_EXP.PcbDoc")
		(comment 1 "Time Appliance Project (Time Card) / footprints 77-91 of 160")
	)
	(layers
		(0 "F.Cu" signal "TOP")
		(4 "In1.Cu" signal "SGND")
		(6 "In2.Cu" signal "IN1")
		(8 "In3.Cu" signal "IN2")
		(10 "In4.Cu" signal "SGND1")
		(2 "B.Cu" signal "BOTTOM")
		(9 "F.Adhes" user "F.Adhesive")
		(11 "B.Adhes" user "B.Adhesive")
		(13 "F.Paste" user "Top Paste")
		(15 "B.Paste" user "Bottom Paste")
		(5 "F.SilkS" user "Top Overlay")
		(7 "B.SilkS" user "Bottom Overlay")
		(1 "F.Mask" user "Top Solder")
		(3 "B.Mask" user "Bottom Solder")
		(17 "Dwgs.User" user "User.Drawings")
		(19 "Cmts.User" user "User.Comments")
		(21 "Eco1.User" user "User.Eco1")
		(23 "Eco2.User" user "User.Eco2")
		(25 "Edge.Cuts" user)
		(27 "Margin" user)
		(31 "F.CrtYd" user "Top Courtyard")
		(29 "B.CrtYd" user "Bottom Courtyard")
		(35 "F.Fab" user "Top Component Center")
		(33 "B.Fab" user "Bottom Component Center")
	)
	(footprint "Vault:M08A_N"
		(layer "F.Cu")
		(at 136.5261 85.9636)
		(property "Reference" "U3"
			(at 2.028595 -2.820479 0)
			(unlocked yes)
			(layer "F.SilkS")
			(effects
				(font
					(size 0.762 0.762)
					(thickness 0.2286)
				)
			)
		)
		(property "Value" "DS90LV027AQMA"
			(at 6.38498 4.359402 0)
			(unlocked yes)
			(layer "F.SilkS")
			(hide yes)
			(effects
				(font
					(size 1.524 1.524)
					(thickness 0.254)
				)
			)
		)
		(sheetname "MAC")
		(sheetfile "MAC.kicad_sch")
		(duplicate_pad_numbers_are_jumpers no)
		(fp_line
			(start -0.9 -2.5)
			(end 0.9 -2.5)
			(stroke
				(width 0.2)
				(type solid)
			)
			(layer "F.SilkS")
		)
		(fp_line
			(start -0.9 2.5)
			(end -0.9 -2.5)
			(stroke
				(width 0.2)
				(type solid)
			)
			(layer "F.SilkS")
		)
		(fp_line
			(start -0.9 2.5)
			(end 0.9 2.5)
			(stroke
				(width 0.2)
				(type solid)
			)
			(layer "F.SilkS")
		)
		(fp_line
			(start 0.9 2.5)
			(end 0.9 -2.5)
			(stroke
				(width 0.2)
				(type solid)
			)
			(layer "F.SilkS")
		)
		(fp_circle
			(center -2.4 -2.755)
			(end -2.4 -2.88)
			(stroke
				(width 0.25)
				(type solid)
			)
			(fill no)
			(layer "F.SilkS")
		)
		(fp_circle
			(center -0.1 -1.7)
			(end -0.1 -1.9)
			(stroke
				(width 0.4)
				(type solid)
			)
			(fill no)
			(layer "F.SilkS")
		)
		(pad "1" smd oval
			(at -2.4 -1.905 90)
			(size 0.6 2.2)
			(layers "F.Cu" "F.Mask" "F.Paste")
			(net "+3.3V")
		)
		(pad "2" smd oval
			(at -2.4 -0.635 90)
			(size 0.6 2.2)
			(layers "F.Cu" "F.Mask" "F.Paste")
			(net "FPGA_MAC_PPS_IN1-")
		)
		(pad "3" smd oval
			(at -2.4 0.635 90)
			(size 0.6 2.2)
			(layers "F.Cu" "F.Mask" "F.Paste")
			(net "FPGA_MAC_PPS_IN0-")
		)
		(pad "4" smd oval
			(at -2.4 1.905 90)
			(size 0.6 2.2)
			(layers "F.Cu" "F.Mask" "F.Paste")
			(net "GND")
		)
		(pad "5" smd oval
			(at 2.4 1.905 90)
			(size 0.6 2.2)
			(layers "F.Cu" "F.Mask" "F.Paste")
			(net "MAC_PPS_IN0-")
		)
		(pad "6" smd oval
			(at 2.4 0.635 90)
			(size 0.6 2.2)
			(layers "F.Cu" "F.Mask" "F.Paste")
			(net "MAC_PPS_IN0+")
		)
		(pad "7" smd oval
			(at 2.4 -0.635 90)
			(size 0.6 2.2)
			(layers "F.Cu" "F.Mask" "F.Paste")
			(net "MAC_PPS_IN1+")
		)
		(pad "8" smd oval
			(at 2.4 -1.905 90)
			(size 0.6 2.2)
			(layers "F.Cu" "F.Mask" "F.Paste")
			(net "MAC_PPS_IN1-")
		)
	)
	(footprint "Vault:RESC1608X55X30NL15T15"
		(layer "F.Cu")
		(at 164.6261 88.5786 90)
		(property "Reference" "R27"
			(at 3.2286 0.026921 90)
			(unlocked yes)
			(layer "F.SilkS")
			(effects
				(font
					(size 0.762 0.762)
					(thickness 0.2286)
				)
			)
		)
		(property "Value" "4.7K"
			(at -3.114802 2.39944 0)
			(unlocked yes)
			(layer "F.SilkS")
			(hide yes)
			(effects
				(font
					(size 1.524 1.524)
					(thickness 0.254)
				)
			)
		)
		(sheetname "GPS_IMU_SENSORS")
		(sheetfile "GPS_IMU_SENSORS.kicad_sch")
		(duplicate_pad_numbers_are_jumpers no)
		(pad "1" smd rect
			(at -0.75 0 180)
			(size 0.95 0.95)
			(layers "F.Cu" "F.Mask" "F.Paste")
			(net "SCL")
		)
		(pad "2" smd rect
			(at 0.75 0 180)
			(size 0.95 0.95)
			(layers "F.Cu" "F.Mask" "F.Paste")
			(net "+3.3V")
		)
	)
	(footprint "Vault:RESC1608X55X25NL10T15"
		(layer "F.Cu")
		(at 123.3761 86.3286 -90)
		(property "Reference" "R13"
			(at -2.2838 -0.023069 270)
			(unlocked yes)
			(layer "F.SilkS")
			(effects
				(font
					(size 0.762 0.762)
					(thickness 0.2286)
				)
			)
		)
		(property "Value" "49.9R"
			(at -2.911602 3.21199 180)
			(unlocked yes)
			(layer "F.SilkS")
			(hide yes)
			(effects
				(font
					(size 1.524 1.524)
					(thickness 0.254)
				)
			)
		)
		(sheetname "MAC")
		(sheetfile "MAC.kicad_sch")
		(duplicate_pad_numbers_are_jumpers no)
		(pad "1" smd rect
			(at -0.7 0)
			(size 0.9 0.7)
			(layers "F.Cu" "F.Mask" "F.Paste")
			(net "NetR13_1")
		)
		(pad "2" smd rect
			(at 0.7 0)
			(size 0.9 0.7)
			(layers "F.Cu" "F.Mask" "F.Paste")
			(net "FPGA_MAC_PPS_OUT-")
		)
	)
	(footprint "SamacSys:155124M173200"
		(layer "F.Cu")
		(at 58.4511 141.8162 90)
		(property "Reference" "D18"
			(at -0.5714 1.701931 90)
			(unlocked yes)
			(layer "F.SilkS")
			(effects
				(font
					(size 0.762 0.762)
					(thickness 0.2286)
				)
			)
		)
		(property "Value" "155124M173200"
			(at 7.1725 2.632202 90)
			(unlocked yes)
			(layer "F.SilkS")
			(hide yes)
			(effects
				(font
					(size 1.524 1.524)
					(thickness 0.254)
				)
			)
		)
		(sheetname "USER_IO_STATUS")
		(sheetfile "USER_IO_STATUS.kicad_sch")
		(duplicate_pad_numbers_are_jumpers no)
		(fp_line
			(start -0.8 0.5)
			(end 0.8 0.5)
			(stroke
				(width 0.1)
				(type solid)
			)
			(layer "F.SilkS")
		)
		(fp_arc
			(start -2 -0.1)
			(mid -1.95 -0.05)
			(end -2 0)
			(stroke
				(width 0.1)
				(type solid)
			)
			(layer "F.SilkS")
		)
		(fp_arc
			(start -2 0)
			(mid -2.05 -0.05)
			(end -2 -0.1)
			(stroke
				(width 0.1)
				(type solid)
			)
			(layer "F.SilkS")
		)
		(pad "1" smd rect
			(at -1.4 0 180)
			(size 0.9 0.6)
			(layers "F.Cu" "F.Mask" "F.Paste")
			(net "+3.3V")
		)
		(pad "2" smd rect
			(at -0.45 -0.325 90)
			(size 0.6 0.55)
			(layers "F.Cu" "F.Mask" "F.Paste")
			(net "NetD18_2")
		)
		(pad "3" smd rect
			(at 0.45 -0.325 90)
			(size 0.6 0.55)
			(layers "F.Cu" "F.Mask" "F.Paste")
			(net "NetD18_3")
		)
		(pad "4" smd rect
			(at 1.4 0 180)
			(size 0.9 0.6)
			(layers "F.Cu" "F.Mask" "F.Paste")
			(net "NetD18_4")
		)
	)
	(footprint "Passives:DIOM1608X06N"
		(layer "F.Cu")
		(at 220.8261 86.7162 180)
		(property "Reference" "D4"
			(at -2 -0.393345 0)
			(unlocked yes)
			(layer "F.SilkS")
			(effects
				(font
					(size 0.762 0.762)
					(thickness 0.2286)
				)
				(justify left bottom)
			)
		)
		(property "Value" "RED"
			(at 18.2973 -9.43439 0)
			(unlocked yes)
			(layer "F.SilkS")
			(hide yes)
			(effects
				(font
					(size 1.524 1.524)
					(thickness 0.254)
				)
				(justify left bottom)
			)
		)
		(sheetname "POWER")
		(sheetfile "POWER.kicad_sch")
		(duplicate_pad_numbers_are_jumpers no)
		(fp_circle
			(center -1.275 -0.725)
			(end -1.275 -0.675)
			(stroke
				(width 0.1)
				(type solid)
			)
			(fill no)
			(layer "F.SilkS")
		)
		(pad "1" smd rect
			(at -0.725 0 270)
			(size 0.85 1)
			(layers "F.Cu" "F.Mask" "F.Paste")
			(net "NetD4_1")
		)
		(pad "2" smd rect
			(at 0.725 0 270)
			(size 0.85 1)
			(layers "F.Cu" "F.Mask" "F.Paste")
			(net "+3.3V")
		)
	)
	(footprint "Vault:RESC1608X55X25NL10T15"
		(layer "F.Cu")
		(at 77.5761 135.6162 180)
		(property "Reference" "R34"
			(at -0.2286 1.473079 0)
			(unlocked yes)
			(layer "F.SilkS")
			(effects
				(font
					(size 0.762 0.762)
					(thickness 0.2286)
				)
			)
		)
		(property "Value" "49.9R"
			(at -2.911602 3.21199 90)
			(unlocked yes)
			(layer "F.SilkS")
			(hide yes)
			(effects
				(font
					(size 1.524 1.524)
					(thickness 0.254)
				)
			)
		)
		(sheetname "USER_IO")
		(sheetfile "USER_IO.kicad_sch")
		(duplicate_pad_numbers_are_jumpers no)
		(pad "1" smd rect
			(at -0.7 0 270)
			(size 0.9 0.7)
			(layers "F.Cu" "F.Mask" "F.Paste")
			(net "NetR34_1")
		)
		(pad "2" smd rect
			(at 0.7 0 270)
			(size 0.9 0.7)
			(layers "F.Cu" "F.Mask" "F.Paste")
			(net "NetAN4_1")
		)
	)
	(footprint "Passives:SOT65P210X110-3N"
		(layer "F.Cu")
		(at 229.6761 137.6412 -90)
		(property "Reference" "D7"
			(at -1.831655 -1.65 0)
			(unlocked yes)
			(layer "F.SilkS")
			(effects
				(font
					(size 0.762 0.762)
					(thickness 0.2286)
				)
				(justify left bottom)
			)
		)
		(property "Value" "BAT54SW"
			(at 0.6448 -1.0501 0)
			(unlocked yes)
			(layer "F.SilkS")
			(hide yes)
			(effects
				(font
					(size 1.524 1.524)
					(thickness 0.254)
				)
				(justify left bottom)
			)
		)
		(sheetname "PCIe_JTAG")
		(sheetfile "PCIe_JTAG.kicad_sch")
		(duplicate_pad_numbers_are_jumpers no)
		(fp_line
			(start 0.675 1.1)
			(end -0.32499 1.1)
			(stroke
				(width 0.2)
				(type solid)
			)
			(layer "F.SilkS")
		)
		(fp_line
			(start 0.675 1.1)
			(end 0.675 0.65)
			(stroke
				(width 0.2)
				(type solid)
			)
			(layer "F.SilkS")
		)
		(fp_line
			(start 0.675 -0.65)
			(end 0.675 -1.1)
			(stroke
				(width 0.2)
				(type solid)
			)
			(layer "F.SilkS")
		)
		(fp_line
			(start 0.675 -1.1)
			(end -0.32499 -1.1)
			(stroke
				(width 0.2)
				(type solid)
			)
			(layer "F.SilkS")
		)
		(fp_circle
			(center -1.125 -1.45)
			(end -1.25 -1.45)
			(stroke
				(width 0.25)
				(type solid)
			)
			(fill no)
			(layer "F.SilkS")
		)
		(pad "1" smd rect
			(at -1.125 -0.65)
			(size 0.5 0.9)
			(layers "F.Cu" "F.Mask" "F.Paste")
			(net "GND")
		)
		(pad "2" smd rect
			(at -1.125 0.65)
			(size 0.5 0.9)
			(layers "F.Cu" "F.Mask" "F.Paste")
			(net "+3.3V")
		)
		(pad "3" smd rect
			(at 1.125 0)
			(size 0.5 0.9)
			(layers "F.Cu" "F.Mask" "F.Paste")
			(net "FPGA_TMS")
		)
	)
	(footprint "Vault:RESC1608X55X30NL15T15"
		(layer "F.Cu")
		(at 82.1261 98.8662 -90)
		(property "Reference" "R15"
			(at 2.7714 -0.026921 90)
			(unlocked yes)
			(layer "F.SilkS")
			(effects
				(font
					(size 0.762 0.762)
					(thickness 0.2286)
				)
			)
		)
		(property "Value" "4.7K"
			(at 2.835402 -4.98946 0)
			(unlocked yes)
			(layer "F.SilkS")
			(hide yes)
			(effects
				(font
					(size 1.524 1.524)
					(thickness 0.254)
				)
			)
		)
		(sheetname "USER_IO")
		(sheetfile "USER_IO.kicad_sch")
		(duplicate_pad_numbers_are_jumpers no)
		(pad "1" smd rect
			(at -0.75 0)
			(size 0.95 0.95)
			(layers "F.Cu" "F.Mask" "F.Paste")
			(net "ANT1_IO_IN")
		)
		(pad "2" smd rect
			(at 0.75 0)
			(size 0.95 0.95)
			(layers "F.Cu" "F.Mask" "F.Paste")
			(net "+3.3V")
		)
	)
	(footprint "Vault:RESC1608X55X30LL15T20"
		(layer "F.Cu")
		(at 179.6261 90.0786 180)
		(property "Reference" "R37"
			(at 2.2714 -0.026921 0)
			(unlocked yes)
			(layer "F.SilkS")
			(effects
				(font
					(size 0.762 0.762)
					(thickness 0.2286)
				)
			)
		)
		(property "Value" "10K"
			(at -2.657602 1.790085 90)
			(unlocked yes)
			(layer "F.SilkS")
			(hide yes)
			(effects
				(font
					(size 1.524 1.524)
					(thickness 0.254)
				)
			)
		)
		(sheetname "GPS_IMU_SENSORS")
		(sheetfile "GPS_IMU_SENSORS.kicad_sch")
		(duplicate_pad_numbers_are_jumpers no)
		(pad "1" smd rect
			(at -0.575 0 270)
			(size 0.85 0.75)
			(layers "F.Cu" "F.Mask" "F.Paste")
			(net "EXT_EEPROM_WP")
		)
		(pad "2" smd rect
			(at 0.575 0 270)
			(size 0.85 0.75)
			(layers "F.Cu" "F.Mask" "F.Paste")
			(net "+3.3V")
		)
	)
	(footprint "Vault:SMTC-TLE-104-01-X-DV"
		(layer "F.Cu")
		(at 84.36315 70.82861 90)
		(property "Reference" "J6"
			(at 5.258558 3.51695 0)
			(unlocked yes)
			(layer "F.SilkS")
			(effects
				(font
					(size 1.524 1.524)
					(thickness 0.254)
				)
			)
		)
		(property "Value" "GNSS Header"
			(at 6.765575 4.994402 90)
			(unlocked yes)
			(layer "F.SilkS")
			(hide yes)
			(effects
				(font
					(size 1.524 1.524)
					(thickness 0.254)
				)
			)
		)
		(sheetname "GPS_IMU_SENSORS")
		(sheetfile "GPS_IMU_SENSORS.kicad_sch")
		(duplicate_pad_numbers_are_jumpers no)
		(fp_line
			(start 4.065 -2)
			(end 4.065 2)
			(stroke
				(width 0.2)
				(type solid)
			)
			(layer "F.SilkS")
		)
		(fp_line
			(start 3.959 -2)
			(end 4.065 -2)
			(stroke
				(width 0.2)
				(type solid)
			)
			(layer "F.SilkS")
		)
		(fp_line
			(start -4.06499 -2)
			(end -3.95899 -2)
			(stroke
				(width 0.2)
				(type solid)
			)
			(layer "F.SilkS")
		)
		(fp_line
			(start -4.06499 -2)
			(end -4.06499 2)
			(stroke
				(width 0.2)
				(type solid)
			)
			(layer "F.SilkS")
		)
		(fp_line
			(start 3.959 2)
			(end 4.065 2)
			(stroke
				(width 0.2)
				(type solid)
			)
			(layer "F.SilkS")
		)
		(fp_line
			(start -4.06499 2)
			(end -3.95899 2)
			(stroke
				(width 0.2)
				(type solid)
			)
			(layer "F.SilkS")
		)
		(fp_circle
			(center -4.41299 -2.286)
			(end -4.28799 -2.286)
			(stroke
				(width 0.25)
				(type solid)
			)
			(fill no)
			(layer "F.SilkS")
		)
		(pad "1" smd rect
			(at -2.99999 -2.43205 90)
			(size 1.1176 1.6891)
			(layers "F.Cu" "F.Mask" "F.Paste")
			(net "+5.0V")
		)
		(pad "2" smd rect
			(at -2.99999 2.43205 90)
			(size 1.1176 1.6891)
			(layers "F.Cu" "F.Mask" "F.Paste")
			(net "+3.3V")
		)
		(pad "3" smd rect
			(at -0.99999 -2.43205 90)
			(size 1.1176 1.6891)
			(layers "F.Cu" "F.Mask" "F.Paste")
			(net "GPS1_TX")
		)
		(pad "4" smd rect
			(at -0.99999 2.43205 90)
			(size 1.1176 1.6891)
			(layers "F.Cu" "F.Mask" "F.Paste")
			(net "GPS1_RST")
		)
		(pad "5" smd rect
			(at 1 -2.43205 90)
			(size 1.1176 1.6891)
			(layers "F.Cu" "F.Mask" "F.Paste")
			(net "GPS1_RX")
		)
		(pad "6" smd rect
			(at 1 2.43205 90)
			(size 1.1176 1.6891)
			(layers "F.Cu" "F.Mask" "F.Paste")
			(net "GPS1_TP1")
		)
		(pad "7" smd rect
			(at 3 -2.43205 90)
			(size 1.1176 1.6891)
			(layers "F.Cu" "F.Mask" "F.Paste")
			(net "GPS1_TP2")
		)
		(pad "8" smd rect
			(at 3 2.43205 90)
			(size 1.1176 1.6891)
			(layers "F.Cu" "F.Mask" "F.Paste")
			(net "GND")
		)
	)
	(footprint "Vault:RESC1608X55X30NL15T15"
		(layer "F.Cu")
		(at 84.1261 98.8662 -90)
		(property "Reference" "R14"
			(at 2.7714 -0.026931 90)
			(unlocked yes)
			(layer "F.SilkS")
			(effects
				(font
					(size 0.762 0.762)
					(thickness 0.2286)
				)
			)
		)
		(property "Value" "4.7K"
			(at 2.835402 -4.73554 0)
			(unlocked yes)
			(layer "F.SilkS")
			(hide yes)
			(effects
				(font
					(size 1.524 1.524)
					(thickness 0.254)
				)
			)
		)
		(sheetname "USER_IO")
		(sheetfile "USER_IO.kicad_sch")
		(duplicate_pad_numbers_are_jumpers no)
		(pad "1" smd rect
			(at -0.75 0)
			(size 0.95 0.95)
			(layers "F.Cu" "F.Mask" "F.Paste")
			(net "ANT1_IO_OUT")
		)
		(pad "2" smd rect
			(at 0.75 0)
			(size 0.95 0.95)
			(layers "F.Cu" "F.Mask" "F.Paste")
			(net "+3.3V")
		)
	)
	(footprint "Vault:CAPC1608X87X45ML20T05"
		(layer "F.Cu")
		(at 130.8761 83.5786)
		(property "Reference" "C23"
			(at -2.1214 -0.135479 0)
			(unlocked yes)
			(layer "F.SilkS")
			(effects
				(font
					(size 0.762 0.762)
					(thickness 0.2286)
				)
			)
		)
		(property "Value" "0.1uF"
			(at 2.09443 2.657602 0)
			(unlocked yes)
			(layer "F.SilkS")
			(hide yes)
			(effects
				(font
					(size 1.524 1.524)
					(thickness 0.254)
				)
			)
		)
		(sheetname "MAC")
		(sheetfile "MAC.kicad_sch")
		(duplicate_pad_numbers_are_jumpers no)
		(pad "1" smd rect
			(at -0.7 0 90)
			(size 1.1 1.05)
			(layers "F.Cu" "F.Mask" "F.Paste")
			(net "GND")
		)
		(pad "2" smd rect
			(at 0.7 0 90)
			(size 1.1 1.05)
			(layers "F.Cu" "F.Mask" "F.Paste")
			(net "+3.3V")
		)
	)
	(footprint "Capacitors:CAPC2012X14N"
		(layer "F.Cu")
		(at 203.0595 116.3062 180)
		(property "Reference" "C6"
			(at 0.3334 -1.416655 180)
			(unlocked yes)
			(layer "F.SilkS")
			(effects
				(font
					(size 0.762 0.762)
					(thickness 0.2286)
				)
				(justify left bottom)
			)
		)
		(property "Value" "CAP_0805_10UF_25V"
			(at -3.8601 8.85681 0)
			(unlocked yes)
			(layer "F.SilkS")
			(hide yes)
			(effects
				(font
					(size 1.524 1.524)
					(thickness 0.254)
				)
				(justify left bottom)
			)
		)
		(sheetname "POWER")
		(sheetfile "POWER.kicad_sch")
		(duplicate_pad_numbers_are_jumpers no)
		(fp_line
			(start 0.762 0.9652)
			(end -0.762 0.9652)
			(stroke
				(width 0.1524)
				(type solid)
			)
			(layer "F.SilkS")
		)
		(fp_line
			(start 0.762 -0.9652)
			(end -0.762 -0.9652)
			(stroke
				(width 0.1524)
				(type solid)
			)
			(layer "F.SilkS")
		)
		(pad "1" smd rect
			(at -0.9 0 270)
			(size 1.45 1.15)
			(layers "F.Cu" "F.Mask" "F.Paste")
			(net "+12V")
		)
		(pad "2" smd rect
			(at 0.9 0 270)
			(size 1.45 1.15)
			(layers "F.Cu" "F.Mask" "F.Paste")
			(net "GND")
		)
	)
	(footprint "Vault:CAPC1608X87X45ML20T05"
		(layer "F.Cu")
		(at 80.3761 98.8662 -90)
		(property "Reference" "C26"
			(at 2.7714 -0.026931 90)
			(unlocked yes)
			(layer "F.SilkS")
			(effects
				(font
					(size 0.762 0.762)
					(thickness 0.2286)
				)
			)
		)
		(property "Value" "0.1uF"
			(at 2.09443 2.657602 270)
			(unlocked yes)
			(layer "F.SilkS")
			(hide yes)
			(effects
				(font
					(size 1.524 1.524)
					(thickness 0.254)
				)
			)
		)
		(sheetname "USER_IO")
		(sheetfile "USER_IO.kicad_sch")
		(duplicate_pad_numbers_are_jumpers no)
		(pad "1" smd rect
			(at -0.7 0)
			(size 1.1 1.05)
			(layers "F.Cu" "F.Mask" "F.Paste")
			(net "+3.3V")
		)
		(pad "2" smd rect
			(at 0.7 0)
			(size 1.1 1.05)
			(layers "F.Cu" "F.Mask" "F.Paste")
			(net "GND")
		)
	)
	(footprint "Vault:RESC1608X55X30NL15T15"
		(layer "F.Cu")
		(at 69.8761 55.6162 90)
		(property "Reference" "R35"
			(at -5.7714 0.026921 90)
			(unlocked yes)
			(layer "F.SilkS")
			(effects
				(font
					(size 0.762 0.762)
					(thickness 0.2286)
				)
			)
		)
		(property "Value" "200 OHM"
			(at -2.962402 4.81166 0)
			(unlocked yes)
			(layer "F.SilkS")
			(hide yes)
			(effects
				(font
					(size 1.524 1.524)
					(thickness 0.254)
				)
			)
		)
		(sheetname "USER_IO_STATUS")
		(sheetfile "USER_IO_STATUS.kicad_sch")
		(duplicate_pad_numbers_are_jumpers no)
		(pad "1" smd rect
			(at -0.675 0 180)
			(size 0.95 0.8)
			(layers "F.Cu" "F.Mask" "F.Paste")
			(net "LED1")
		)
		(pad "2" smd rect
			(at 0.675 0 180)
			(size 0.95 0.8)
			(layers "F.Cu" "F.Mask" "F.Paste")
			(net "NetD3_1")
		)
	)
)
